# BASEBOARD_FAB2 (Tioga Pass) — schematic netlist excerpt (pin names and nets, part order shuffled) for the footprints in the layout excerpt that follows; sources: Cadence DE-HDL packaged netlist, KiCad conversion of Wiwynn_Tioga_Pass_MB.brd

R6N15  RES  1.00K 1% CHIP  pkg 0402  page 156 : A = GND ; B = PD_PIROM_CPU0_ADDR2
CT37  CAP  1000PF 50V 10% X7R  pkg 0402LF  page 203 : A = A_TSENSE_PVCCIN_CPU0 ; B = GND
C2T13  CAP  0.22UF 16V 10% X7R  pkg 0402  page 185 : A = P3E_PCH_M2_TX_C_DP<2> ; B = P3E_PCH_M2_TX_DP<2>

(kicad_pcb
	(version 20260206)
	(generator "pcbnew")
	(generator_version "10.0")
	(general
		(thickness 1.6)
		(legacy_teardrops no)
	)
	(paper "A4")
	(title_block
		(title "Wiwynn_Tioga_Pass_MB.brd")
		(comment 1 "Tioga Pass / footprints 3519-3521 of 4770")
	)
	(layers
		(0 "F.Cu" signal "TOP")
		(4 "In1.Cu" signal "L2GND")
		(6 "In2.Cu" signal "L3")
		(8 "In3.Cu" signal "L4GND")
		(10 "In4.Cu" signal "L5")
		(12 "In5.Cu" signal "L6GND")
		(14 "In6.Cu" signal "L7VCC")
		(16 "In7.Cu" signal "L8VCC")
		(18 "In8.Cu" signal "L9GND")
		(20 "In9.Cu" signal "L10")
		(22 "In10.Cu" signal "L11GND")
		(24 "In11.Cu" signal "L12")
		(26 "In12.Cu" signal "L13GND")
		(2 "B.Cu" signal "BOTTOM")
		(9 "F.Adhes" user "F.Adhesive")
		(11 "B.Adhes" user "B.Adhesive")
		(13 "F.Paste" user "Package Geometry/Pastemask Top")
		(15 "B.Paste" user "Package Geometry/Pastemask Bottom")
		(5 "F.SilkS" user "Ref Des/Silkscreen Top")
		(7 "B.SilkS" user "Ref Des/Silkscreen Bottom")
		(1 "F.Mask" user "Board Geometry/Soldermask Top")
		(3 "B.Mask" user "Board Geometry/Soldermask Bottom")
		(17 "Dwgs.User" user "User.Drawings")
		(19 "Cmts.User" user "User.Comments")
		(21 "Eco1.User" user "User.Eco1")
		(23 "Eco2.User" user "User.Eco2")
		(25 "Edge.Cuts" user "Board Geometry/Outline")
		(27 "Margin" user)
		(31 "F.CrtYd" user "Package Geometry/Place Bound Top")
		(29 "B.CrtYd" user "Package Geometry/Place Bound Bottom")
		(35 "F.Fab" user "Ref Des/Assembly Top")
		(33 "B.Fab" user "Ref Des/Assembly Bottom")
	)
	(footprint ""
		(layer "B.Cu")
		(at 195.1736 -72.1614 90)
		(property "Reference" "CT37"
			(at 0.8382 -0.84963 90)
			(unlocked yes)
			(layer "B.SilkS")
			(effects
				(font
					(size 0.7874 0.5842)
					(thickness 0.1524)
				)
				(justify left mirror)
			)
		)
		(property "Value" ""
			(at 0 0 90)
			(layer "B.Fab")
			(effects
				(font
					(size 1.27 1.27)
				)
				(justify mirror)
			)
		)
		(duplicate_pad_numbers_are_jumpers no)
		(fp_poly
			(pts
				(xy -0.3048 -0.1016) (xy -0.3048 0.9906) (xy 0.3048 0.9906) (xy 0.3048 -0.1016)
			)
			(stroke
				(width 0)
				(type default)
			)
			(fill no)
			(layer "B.CrtYd")
		)
		(fp_line
			(start 0.3048 -0.1016)
			(end 0.3048 0.9906)
			(stroke
				(width 0.1)
				(type default)
			)
			(layer "B.Fab")
		)
		(fp_line
			(start -0.3048 -0.1016)
			(end 0.3048 -0.1016)
			(stroke
				(width 0.1)
				(type default)
			)
			(layer "B.Fab")
		)
		(fp_line
			(start 0.3048 0.9906)
			(end -0.3048 0.9906)
			(stroke
				(width 0.1)
				(type default)
			)
			(layer "B.Fab")
		)
		(fp_line
			(start -0.3048 0.9906)
			(end -0.3048 -0.1016)
			(stroke
				(width 0.1)
				(type default)
			)
			(layer "B.Fab")
		)
		(pad "1" smd rect
			(at 0 0 270)
			(size 0.508 0.508)
			(layers "B.Cu" "B.Mask" "B.Paste")
			(net "A_TSENSE_PVCCIN_CPU0")
		)
		(pad "2" smd rect
			(at 0 0.889 270)
			(size 0.508 0.508)
			(layers "B.Cu" "B.Mask" "B.Paste")
			(net "GND")
		)
		(zone
			(layer "B.Cu")
			(hatch none 0.5)
			(connect_pads
				(clearance 0)
			)
			(min_thickness 0.25)
			(keepout
				(tracks allowed)
				(vias not_allowed)
				(pads allowed)
				(copperpour not_allowed)
				(footprints allowed)
			)
			(placement
				(enabled no)
				(sheetname "")
			)
			(fill
				(thermal_gap 0.5)
				(thermal_bridge_width 0.5)
				(island_removal_mode 0)
			)
			(polygon
				(pts
					(xy 195.4276 -72.4154) (xy 195.4276 -71.9074) (xy 195.8086 -71.9074) (xy 195.8086 -72.4154)
				)
			)
		)
		(zone
			(layer "B.Cu")
			(hatch none 0.5)
			(connect_pads
				(clearance 0)
			)
			(min_thickness 0.25)
			(keepout
				(tracks not_allowed)
				(vias allowed)
				(pads allowed)
				(copperpour not_allowed)
				(footprints allowed)
			)
			(placement
				(enabled no)
				(sheetname "")
			)
			(fill
				(thermal_gap 0.5)
				(thermal_bridge_width 0.5)
				(island_removal_mode 0)
			)
			(polygon
				(pts
					(xy 195.8086 -72.4154) (xy 195.8086 -71.9074) (xy 195.4276 -71.9074) (xy 195.4276 -72.4154)
				)
			)
		)
	)
	(footprint ""
		(layer "B.Cu")
		(at 385.463034 -27.522932 90)
		(property "Reference" "C2T13"
			(at 0 0 90)
			(layer "B.SilkS")
			(hide yes)
			(effects
				(font
					(size 1.27 1.27)
				)
				(justify mirror)
			)
		)
		(property "Value" ""
			(at 0 0 90)
			(layer "B.Fab")
			(effects
				(font
					(size 1.27 1.27)
				)
				(justify mirror)
			)
		)
		(duplicate_pad_numbers_are_jumpers no)
		(fp_poly
			(pts
				(xy -0.3048 -0.1016) (xy -0.3048 0.9906) (xy 0.3048 0.9906) (xy 0.3048 -0.1016)
			)
			(stroke
				(width 0)
				(type default)
			)
			(fill no)
			(layer "B.CrtYd")
		)
		(fp_line
			(start 0.3048 -0.1016)
			(end 0.3048 0.9906)
			(stroke
				(width 0.1)
				(type default)
			)
			(layer "B.Fab")
		)
		(fp_line
			(start -0.3048 -0.1016)
			(end 0.3048 -0.1016)
			(stroke
				(width 0.1)
				(type default)
			)
			(layer "B.Fab")
		)
		(fp_line
			(start 0.3048 0.9906)
			(end -0.3048 0.9906)
			(stroke
				(width 0.1)
				(type default)
			)
			(layer "B.Fab")
		)
		(fp_line
			(start -0.3048 0.9906)
			(end -0.3048 -0.1016)
			(stroke
				(width 0.1)
				(type default)
			)
			(layer "B.Fab")
		)
		(pad "1" smd rect
			(at 0 0 270)
			(size 0.508 0.508)
			(layers "B.Cu" "B.Mask" "B.Paste")
			(net "P3E_PCH_M2_TX_C_DP<2>")
		)
		(pad "2" smd rect
			(at 0 0.889 270)
			(size 0.508 0.508)
			(layers "B.Cu" "B.Mask" "B.Paste")
			(net "P3E_PCH_M2_TX_DP<2>")
		)
		(zone
			(layer "B.Cu")
			(hatch none 0.5)
			(connect_pads
				(clearance 0)
			)
			(min_thickness 0.25)
			(keepout
				(tracks allowed)
				(vias not_allowed)
				(pads allowed)
				(copperpour not_allowed)
				(footprints allowed)
			)
			(placement
				(enabled no)
				(sheetname "")
			)
			(fill
				(thermal_gap 0.5)
				(thermal_bridge_width 0.5)
				(island_removal_mode 0)
			)
			(polygon
				(pts
					(xy 385.717034 -27.776932) (xy 385.717034 -27.268932) (xy 386.098034 -27.268932) (xy 386.098034 -27.776932)
				)
			)
		)
		(zone
			(layer "B.Cu")
			(hatch none 0.5)
			(connect_pads
				(clearance 0)
			)
			(min_thickness 0.25)
			(keepout
				(tracks not_allowed)
				(vias allowed)
				(pads allowed)
				(copperpour not_allowed)
				(footprints allowed)
			)
			(placement
				(enabled no)
				(sheetname "")
			)
			(fill
				(thermal_gap 0.5)
				(thermal_bridge_width 0.5)
				(island_removal_mode 0)
			)
			(polygon
				(pts
					(xy 386.098034 -27.776932) (xy 386.098034 -27.268932) (xy 385.717034 -27.268932) (xy 385.717034 -27.776932)
				)
			)
		)
	)
	(footprint ""
		(layer "B.Cu")
		(at 195.4784 -102.6414 180)
		(property "Reference" "R6N15"
			(at 0 0 0)
			(layer "B.SilkS")
			(hide yes)
			(effects
				(font
					(size 1.27 1.27)
				)
				(justify mirror)
			)
		)
		(property "Value" ""
			(at 0 0 0)
			(layer "B.Fab")
			(effects
				(font
					(size 1.27 1.27)
				)
				(justify mirror)
			)
		)
		(duplicate_pad_numbers_are_jumpers no)
		(fp_poly
			(pts
				(xy 0.2794 -0.1016) (xy -0.2794 -0.1016) (xy -0.2794 0.9906) (xy 0.2794 0.9906)
			)
			(stroke
				(width 0)
				(type default)
			)
			(fill no)
			(layer "B.CrtYd")
		)
		(fp_line
			(start 0.2794 0.9906)
			(end -0.2794 0.9906)
			(stroke
				(width 0.1)
				(type default)
			)
			(layer "B.Fab")
		)
		(fp_line
			(start 0.2794 -0.1016)
			(end 0.2794 0.9906)
			(stroke
				(width 0.1)
				(type default)
			)
			(layer "B.Fab")
		)
		(fp_line
			(start -0.2794 0.9906)
			(end -0.2794 -0.1016)
			(stroke
				(width 0.1)
				(type default)
			)
			(layer "B.Fab")
		)
		(fp_line
			(start -0.2794 -0.1016)
			(end 0.2794 -0.1016)
			(stroke
				(width 0.1)
				(type default)
			)
			(layer "B.Fab")
		)
		(pad "1" smd rect
			(at 0 0)
			(size 0.508 0.508)
			(layers "B.Cu" "B.Mask" "B.Paste")
			(net "GND")
		)
		(pad "2" smd rect
			(at 0 0.889)
			(size 0.508 0.508)
			(layers "B.Cu" "B.Mask" "B.Paste")
			(net "PD_PIROM_CPU0_ADDR2")
		)
		(zone
			(layer "B.Cu")
			(hatch none 0.5)
			(connect_pads
				(clearance 0)
			)
			(min_thickness 0.25)
			(keepout
				(tracks not_allowed)
				(vias allowed)
				(pads allowed)
				(copperpour not_allowed)
				(footprints allowed)
			)
			(placement
				(enabled no)
				(sheetname "")
			)
			(fill
				(thermal_gap 0.5)
				(thermal_bridge_width 0.5)
				(island_removal_mode 0)
			)
			(polygon
				(pts
					(xy 195.2244 -103.2764) (xy 195.7324 -103.2764) (xy 195.7324 -102.8954) (xy 195.2244 -102.8954)
				)
			)
		)
		(zone
			(layer "B.Cu")
			(hatch none 0.5)
			(connect_pads
				(clearance 0)
			)
			(min_thickness 0.25)
			(keepout
				(tracks allowed)
				(vias not_allowed)
				(pads allowed)
				(copperpour not_allowed)
				(footprints allowed)
			)
			(placement
				(enabled no)
				(sheetname "")
			)
			(fill
				(thermal_gap 0.5)
				(thermal_bridge_width 0.5)
				(island_removal_mode 0)
			)
			(polygon
				(pts
					(xy 195.2244 -102.8954) (xy 195.7324 -102.8954) (xy 195.7324 -103.2764) (xy 195.2244 -103.2764)
				)
			)
		)
	)
)
